# BASEBOARD_FAB2 (Tioga Pass) — schematic netlist excerpt (pin names and nets, part order shuffled) for the footprints in the layout excerpt that follows; sources: Cadence DE-HDL packaged netlist, KiCad conversion of Wiwynn_Tioga_Pass_MB.brd

C1D12  CAP  1.0UF 16V 10% X6S  pkg 0402  page 208 : A = VR_FET_SW_P12V_STBY_PVCCIN_CPU1 ; B = GND
R4E21  RES  68.1K 1% EMPTY  pkg 0402  page 214 : A = VR_PVCCIO_CPU1_OCSET ; B = GND
R2N1  RES  33.2 1% CHIP  pkg 0402  page 119 : A = FM_CPU_CATERR_DLY_LVT3_R_N ; B = FM_CPU_CATERR_DLY_LVT3_N

(kicad_pcb
	(version 20260206)
	(generator "pcbnew")
	(generator_version "10.0")
	(general
		(thickness 1.6)
		(legacy_teardrops no)
	)
	(paper "A4")
	(title_block
		(title "Wiwynn_Tioga_Pass_MB.brd")
		(comment 1 "Tioga Pass / footprints 1768-1770 of 4770")
	)
	(layers
		(0 "F.Cu" signal "TOP")
		(4 "In1.Cu" signal "L2GND")
		(6 "In2.Cu" signal "L3")
		(8 "In3.Cu" signal "L4GND")
		(10 "In4.Cu" signal "L5")
		(12 "In5.Cu" signal "L6GND")
		(14 "In6.Cu" signal "L7VCC")
		(16 "In7.Cu" signal "L8VCC")
		(18 "In8.Cu" signal "L9GND")
		(20 "In9.Cu" signal "L10")
		(22 "In10.Cu" signal "L11GND")
		(24 "In11.Cu" signal "L12")
		(26 "In12.Cu" signal "L13GND")
		(2 "B.Cu" signal "BOTTOM")
		(9 "F.Adhes" user "F.Adhesive")
		(11 "B.Adhes" user "B.Adhesive")
		(13 "F.Paste" user "Package Geometry/Pastemask Top")
		(15 "B.Paste" user "Package Geometry/Pastemask Bottom")
		(5 "F.SilkS" user "Ref Des/Silkscreen Top")
		(7 "B.SilkS" user "Ref Des/Silkscreen Bottom")
		(1 "F.Mask" user "Board Geometry/Soldermask Top")
		(3 "B.Mask" user "Board Geometry/Soldermask Bottom")
		(17 "Dwgs.User" user "User.Drawings")
		(19 "Cmts.User" user "User.Comments")
		(21 "Eco1.User" user "User.Eco1")
		(23 "Eco2.User" user "User.Eco2")
		(25 "Edge.Cuts" user "Board Geometry/Outline")
		(27 "Margin" user)
		(31 "F.CrtYd" user "Package Geometry/Place Bound Top")
		(29 "B.CrtYd" user "Package Geometry/Place Bound Bottom")
		(35 "F.Fab" user "Ref Des/Assembly Top")
		(33 "B.Fab" user "Ref Des/Assembly Bottom")
	)
	(footprint ""
		(layer "F.Cu")
		(at 182.372 -56.1594 180)
		(property "Reference" "R4E21"
			(at 0 0 180)
			(layer "F.SilkS")
			(hide yes)
			(effects
				(font
					(size 1.27 1.27)
				)
			)
		)
		(property "Value" ""
			(at 0 0 180)
			(layer "F.Fab")
			(effects
				(font
					(size 1.27 1.27)
				)
			)
		)
		(duplicate_pad_numbers_are_jumpers no)
		(fp_poly
			(pts
				(xy -0.2794 -0.1016) (xy 0.2794 -0.1016) (xy 0.2794 0.9906) (xy -0.2794 0.9906)
			)
			(stroke
				(width 0)
				(type default)
			)
			(fill no)
			(layer "F.CrtYd")
		)
		(fp_line
			(start 0.2794 0.9906)
			(end 0.2794 -0.1016)
			(stroke
				(width 0.1)
				(type default)
			)
			(layer "F.Fab")
		)
		(fp_line
			(start 0.2794 -0.1016)
			(end -0.2794 -0.1016)
			(stroke
				(width 0.1)
				(type default)
			)
			(layer "F.Fab")
		)
		(fp_line
			(start -0.2794 0.9906)
			(end 0.2794 0.9906)
			(stroke
				(width 0.1)
				(type default)
			)
			(layer "F.Fab")
		)
		(fp_line
			(start -0.2794 -0.1016)
			(end -0.2794 0.9906)
			(stroke
				(width 0.1)
				(type default)
			)
			(layer "F.Fab")
		)
		(pad "1" smd rect
			(at 0 0 180)
			(size 0.508 0.508)
			(layers "F.Cu" "F.Mask" "F.Paste")
			(net "VR_PVCCIO_CPU1_OCSET")
		)
		(pad "2" smd rect
			(at 0 0.889 180)
			(size 0.508 0.508)
			(layers "F.Cu" "F.Mask" "F.Paste")
			(net "GND")
		)
		(zone
			(layer "F.Cu")
			(hatch none 0.5)
			(connect_pads
				(clearance 0)
			)
			(min_thickness 0.25)
			(keepout
				(tracks not_allowed)
				(vias allowed)
				(pads allowed)
				(copperpour not_allowed)
				(footprints allowed)
			)
			(placement
				(enabled no)
				(sheetname "")
			)
			(fill
				(thermal_gap 0.5)
				(thermal_bridge_width 0.5)
				(island_removal_mode 0)
			)
			(polygon
				(pts
					(xy 182.626 -56.7944) (xy 182.118 -56.7944) (xy 182.118 -56.4134) (xy 182.626 -56.4134)
				)
			)
		)
		(zone
			(layer "F.Cu")
			(hatch none 0.5)
			(connect_pads
				(clearance 0)
			)
			(min_thickness 0.25)
			(keepout
				(tracks allowed)
				(vias not_allowed)
				(pads allowed)
				(copperpour not_allowed)
				(footprints allowed)
			)
			(placement
				(enabled no)
				(sheetname "")
			)
			(fill
				(thermal_gap 0.5)
				(thermal_bridge_width 0.5)
				(island_removal_mode 0)
			)
			(polygon
				(pts
					(xy 182.626 -56.4134) (xy 182.118 -56.4134) (xy 182.118 -56.7944) (xy 182.626 -56.7944)
				)
			)
		)
	)
	(footprint ""
		(layer "F.Cu")
		(at 29.6164 -83.963002 -90)
		(property "Reference" "C1D12"
			(at 0 0 270)
			(layer "F.SilkS")
			(hide yes)
			(effects
				(font
					(size 1.27 1.27)
				)
			)
		)
		(property "Value" ""
			(at 0 0 270)
			(layer "F.Fab")
			(effects
				(font
					(size 1.27 1.27)
				)
			)
		)
		(duplicate_pad_numbers_are_jumpers no)
		(fp_rect
			(start 0.3048 -0.1016)
			(end -0.3048 0.9906)
			(stroke
				(width 0)
				(type default)
			)
			(fill no)
			(layer "F.CrtYd")
		)
		(fp_line
			(start -0.3048 0.9906)
			(end 0.3048 0.9906)
			(stroke
				(width 0.1)
				(type default)
			)
			(layer "F.Fab")
		)
		(fp_line
			(start 0.3048 0.9906)
			(end 0.3048 -0.1016)
			(stroke
				(width 0.1)
				(type default)
			)
			(layer "F.Fab")
		)
		(fp_line
			(start -0.3048 -0.1016)
			(end -0.3048 0.9906)
			(stroke
				(width 0.1)
				(type default)
			)
			(layer "F.Fab")
		)
		(fp_line
			(start 0.3048 -0.1016)
			(end -0.3048 -0.1016)
			(stroke
				(width 0.1)
				(type default)
			)
			(layer "F.Fab")
		)
		(pad "1" smd rect
			(at 0 0 270)
			(size 0.508 0.508)
			(layers "F.Cu" "F.Mask" "F.Paste")
			(net "VR_FET_SW_P12V_STBY_PVCCIN_CPU1")
		)
		(pad "2" smd rect
			(at 0 0.889 270)
			(size 0.508 0.508)
			(layers "F.Cu" "F.Mask" "F.Paste")
			(net "GND")
		)
		(zone
			(layer "F.Cu")
			(hatch none 0.5)
			(connect_pads
				(clearance 0)
			)
			(min_thickness 0.25)
			(keepout
				(tracks allowed)
				(vias not_allowed)
				(pads allowed)
				(copperpour not_allowed)
				(footprints allowed)
			)
			(placement
				(enabled no)
				(sheetname "")
			)
			(fill
				(thermal_gap 0.5)
				(thermal_bridge_width 0.5)
				(island_removal_mode 0)
			)
			(polygon
				(pts
					(xy 29.3624 -83.709002) (xy 29.3624 -84.217002) (xy 28.9814 -84.217002) (xy 28.9814 -83.709002)
				)
			)
		)
		(zone
			(layer "F.Cu")
			(hatch none 0.5)
			(connect_pads
				(clearance 0)
			)
			(min_thickness 0.25)
			(keepout
				(tracks not_allowed)
				(vias allowed)
				(pads allowed)
				(copperpour not_allowed)
				(footprints allowed)
			)
			(placement
				(enabled no)
				(sheetname "")
			)
			(fill
				(thermal_gap 0.5)
				(thermal_bridge_width 0.5)
				(island_removal_mode 0)
			)
			(polygon
				(pts
					(xy 29.3624 -83.709002) (xy 29.3624 -84.217002) (xy 28.9814 -84.217002) (xy 28.9814 -83.709002)
				)
			)
		)
	)
	(footprint ""
		(layer "F.Cu")
		(at 417.43122 -111.19612)
		(property "Reference" "R2N1"
			(at 0 0 0)
			(layer "F.SilkS")
			(hide yes)
			(effects
				(font
					(size 1.27 1.27)
				)
			)
		)
		(property "Value" ""
			(at 0 0 0)
			(layer "F.Fab")
			(effects
				(font
					(size 1.27 1.27)
				)
			)
		)
		(duplicate_pad_numbers_are_jumpers no)
		(fp_poly
			(pts
				(xy -0.2794 -0.1016) (xy 0.2794 -0.1016) (xy 0.2794 0.9906) (xy -0.2794 0.9906)
			)
			(stroke
				(width 0)
				(type default)
			)
			(fill no)
			(layer "F.CrtYd")
		)
		(fp_line
			(start -0.2794 -0.1016)
			(end -0.2794 0.9906)
			(stroke
				(width 0.1)
				(type default)
			)
			(layer "F.Fab")
		)
		(fp_line
			(start -0.2794 0.9906)
			(end 0.2794 0.9906)
			(stroke
				(width 0.1)
				(type default)
			)
			(layer "F.Fab")
		)
		(fp_line
			(start 0.2794 -0.1016)
			(end -0.2794 -0.1016)
			(stroke
				(width 0.1)
				(type default)
			)
			(layer "F.Fab")
		)
		(fp_line
			(start 0.2794 0.9906)
			(end 0.2794 -0.1016)
			(stroke
				(width 0.1)
				(type default)
			)
			(layer "F.Fab")
		)
		(pad "1" smd rect
			(at 0 0)
			(size 0.508 0.508)
			(layers "F.Cu" "F.Mask" "F.Paste")
			(net "FM_CPU_CATERR_DLY_LVT3_R_N")
		)
		(pad "2" smd rect
			(at 0 0.889)
			(size 0.508 0.508)
			(layers "F.Cu" "F.Mask" "F.Paste")
			(net "FM_CPU_CATERR_DLY_LVT3_N")
		)
		(zone
			(layer "F.Cu")
			(hatch none 0.5)
			(connect_pads
				(clearance 0)
			)
			(min_thickness 0.25)
			(keepout
				(tracks allowed)
				(vias not_allowed)
				(pads allowed)
				(copperpour not_allowed)
				(footprints allowed)
			)
			(placement
				(enabled no)
				(sheetname "")
			)
			(fill
				(thermal_gap 0.5)
				(thermal_bridge_width 0.5)
				(island_removal_mode 0)
			)
			(polygon
				(pts
					(xy 417.17722 -110.94212) (xy 417.68522 -110.94212) (xy 417.68522 -110.56112) (xy 417.17722 -110.56112)
				)
			)
		)
		(zone
			(layer "F.Cu")
			(hatch none 0.5)
			(connect_pads
				(clearance 0)
			)
			(min_thickness 0.25)
			(keepout
				(tracks not_allowed)
				(vias allowed)
				(pads allowed)
				(copperpour not_allowed)
				(footprints allowed)
			)
			(placement
				(enabled no)
				(sheetname "")
			)
			(fill
				(thermal_gap 0.5)
				(thermal_bridge_width 0.5)
				(island_removal_mode 0)
			)
			(polygon
				(pts
					(xy 417.17722 -110.56112) (xy 417.68522 -110.56112) (xy 417.68522 -110.94212) (xy 417.17722 -110.94212)
				)
			)
		)
	)
)
